(kicad_pcb
	(version 20260206)
	(generator "pcbnew")
	(generator_version "10.0")
	(general
		(thickness 1.6)
		(legacy_teardrops no)
	)
	(paper "A4")
	(title_block
		(title "fcb — Lightning_FCB_BRD.brd")
		(comment 1 "Lightning (Wiwynn / Facebook NVMe JBOF) / footprints 404-411 of 495")
	)
	(layers
		(0 "F.Cu" signal "TOP")
		(4 "In1.Cu" signal "L2GND")
		(6 "In2.Cu" signal "L3VCC")
		(2 "B.Cu" signal "BOTTOM")
		(9 "F.Adhes" user "F.Adhesive")
		(11 "B.Adhes" user "B.Adhesive")
		(13 "F.Paste" user "Package Geometry/Pastemask Top")
		(15 "B.Paste" user "Package Geometry/Pastemask Bottom")
		(5 "F.SilkS" user "Ref Des/Silkscreen Top")
		(7 "B.SilkS" user "Ref Des/Silkscreen Bottom")
		(1 "F.Mask" user "Board Geometry/Soldermask Top")
		(3 "B.Mask" user "Board Geometry/Soldermask Bottom")
		(17 "Dwgs.User" user "User.Drawings")
		(19 "Cmts.User" user "User.Comments")
		(21 "Eco1.User" user "User.Eco1")
		(23 "Eco2.User" user "User.Eco2")
		(25 "Edge.Cuts" user "Board Geometry/Outline")
		(27 "Margin" user)
		(31 "F.CrtYd" user "Package Geometry/Place Bound Top")
		(29 "B.CrtYd" user "Package Geometry/Place Bound Bottom")
		(35 "F.Fab" user "Ref Des/Assembly Top")
		(33 "B.Fab" user "Ref Des/Assembly Bottom")
	)
	(footprint ""
		(layer "F.Cu")
		(at 10.0838 -278.384 -90)
		(property "Reference" "R117"
			(at 0 0 270)
			(layer "F.SilkS")
			(hide yes)
			(effects
				(font
					(size 1.27 1.27)
				)
			)
		)
		(property "Value" "2KR2F-3-GP"
			(at 0.064008 -3.993896 270)
			(unlocked yes)
			(layer "F.Fab")
			(hide yes)
			(effects
				(font
					(size 1.016 1.016)
					(thickness 0.1524)
				)
			)
		)
		(property "Device Type" "R402H16"
			(at 0.064008 -5.517896 270)
			(unlocked yes)
			(layer "F.Fab")
			(hide yes)
			(effects
				(font
					(size 1.016 1.016)
					(thickness 0.1524)
				)
			)
		)
		(duplicate_pad_numbers_are_jumpers no)
		(fp_line
			(start -0.508 -0.9398)
			(end -0.508 0.9398)
			(stroke
				(width 0.1524)
				(type default)
			)
			(layer "F.SilkS")
		)
		(fp_line
			(start 0.508 -0.9398)
			(end -0.508 -0.9398)
			(stroke
				(width 0.1524)
				(type default)
			)
			(layer "F.SilkS")
		)
		(fp_rect
			(start -0.508 0.9398)
			(end 0.508 -0.9398)
			(stroke
				(width 0)
				(type default)
			)
			(fill no)
			(layer "F.CrtYd")
		)
		(fp_rect
			(start -0.508 0.9398)
			(end 0.508 -0.9398)
			(stroke
				(width 0)
				(type default)
			)
			(fill no)
			(layer "F.Fab")
		)
		(pad "1" smd custom
			(at 0 -0.4445 270)
			(size 0.1397 0.1397)
			(layers "F.Cu" "F.Mask" "F.Paste")
			(net "LED_DR_LED2")
			(options
				(clearance outline)
				(anchor circle)
			)
			(primitives
				(gr_poly
					(pts
						(arc
							(start -0.1778 -0.2794)
							(mid -0.249642 -0.249642)
							(end -0.2794 -0.1778)
						)
						(arc
							(start -0.2794 0.1778)
							(mid -0.249642 0.249642)
							(end -0.1778 0.2794)
						)
						(arc
							(start 0.1778 0.2794)
							(mid 0.249642 0.249642)
							(end 0.2794 0.1778)
						)
						(arc
							(start 0.2794 -0.1778)
							(mid 0.249642 -0.249642)
							(end 0.1778 -0.2794)
						)
					)
					(width 0)
					(fill yes)
				)
			)
		)
		(pad "2" smd custom
			(at 0 0.4445 270)
			(size 0.1397 0.1397)
			(layers "F.Cu" "F.Mask" "F.Paste")
			(net "LED_DR_LED2_B")
			(options
				(clearance outline)
				(anchor circle)
			)
			(primitives
				(gr_poly
					(pts
						(arc
							(start -0.1778 -0.2794)
							(mid -0.249642 -0.249642)
							(end -0.2794 -0.1778)
						)
						(arc
							(start -0.2794 0.1778)
							(mid -0.249642 0.249642)
							(end -0.1778 0.2794)
						)
						(arc
							(start 0.1778 0.2794)
							(mid 0.249642 0.249642)
							(end 0.2794 0.1778)
						)
						(arc
							(start 0.2794 -0.1778)
							(mid 0.249642 -0.249642)
							(end 0.1778 -0.2794)
						)
					)
					(width 0)
					(fill yes)
				)
			)
		)
	)
	(footprint ""
		(layer "F.Cu")
		(at 14.8844 -71.12 -90)
		(property "Reference" "R167"
			(at 0 0 270)
			(layer "F.SilkS")
			(hide yes)
			(effects
				(font
					(size 1.27 1.27)
				)
			)
		)
		(property "Value" "4K7R2F-GP"
			(at 0.064008 -3.993896 270)
			(unlocked yes)
			(layer "F.Fab")
			(hide yes)
			(effects
				(font
					(size 1.016 1.016)
					(thickness 0.1524)
				)
			)
		)
		(property "Device Type" "R402H16"
			(at 0.064008 -5.517896 270)
			(unlocked yes)
			(layer "F.Fab")
			(hide yes)
			(effects
				(font
					(size 1.016 1.016)
					(thickness 0.1524)
				)
			)
		)
		(duplicate_pad_numbers_are_jumpers no)
		(fp_line
			(start -0.508 -0.9398)
			(end -0.508 0.9398)
			(stroke
				(width 0.1524)
				(type default)
			)
			(layer "F.SilkS")
		)
		(fp_line
			(start 0.508 -0.9398)
			(end -0.508 -0.9398)
			(stroke
				(width 0.1524)
				(type default)
			)
			(layer "F.SilkS")
		)
		(fp_rect
			(start -0.508 0.9398)
			(end 0.508 -0.9398)
			(stroke
				(width 0)
				(type default)
			)
			(fill no)
			(layer "F.CrtYd")
		)
		(fp_rect
			(start -0.508 0.9398)
			(end 0.508 -0.9398)
			(stroke
				(width 0)
				(type default)
			)
			(fill no)
			(layer "F.Fab")
		)
		(pad "1" smd custom
			(at 0 -0.4445 270)
			(size 0.1397 0.1397)
			(layers "F.Cu" "F.Mask" "F.Paste")
			(net "P3V3")
			(options
				(clearance outline)
				(anchor circle)
			)
			(primitives
				(gr_poly
					(pts
						(arc
							(start -0.1778 -0.2794)
							(mid -0.249642 -0.249642)
							(end -0.2794 -0.1778)
						)
						(arc
							(start -0.2794 0.1778)
							(mid -0.249642 0.249642)
							(end -0.1778 0.2794)
						)
						(arc
							(start 0.1778 0.2794)
							(mid 0.249642 0.249642)
							(end 0.2794 0.1778)
						)
						(arc
							(start 0.2794 -0.1778)
							(mid 0.249642 -0.249642)
							(end 0.1778 -0.2794)
						)
					)
					(width 0)
					(fill yes)
				)
			)
		)
		(pad "2" smd custom
			(at 0 0.4445 270)
			(size 0.1397 0.1397)
			(layers "F.Cu" "F.Mask" "F.Paste")
			(net "PWM_BUFFER_IN_FAN1_FAN2")
			(options
				(clearance outline)
				(anchor circle)
			)
			(primitives
				(gr_poly
					(pts
						(arc
							(start -0.1778 -0.2794)
							(mid -0.249642 -0.249642)
							(end -0.2794 -0.1778)
						)
						(arc
							(start -0.2794 0.1778)
							(mid -0.249642 0.249642)
							(end -0.1778 0.2794)
						)
						(arc
							(start 0.1778 0.2794)
							(mid 0.249642 0.249642)
							(end 0.2794 0.1778)
						)
						(arc
							(start 0.2794 -0.1778)
							(mid 0.249642 -0.249642)
							(end 0.1778 -0.2794)
						)
					)
					(width 0)
					(fill yes)
				)
			)
		)
	)
	(footprint ""
		(layer "F.Cu")
		(at 21.7678 -218.821 90)
		(property "Reference" "R134"
			(at 0 0 90)
			(layer "F.SilkS")
			(hide yes)
			(effects
				(font
					(size 1.27 1.27)
				)
			)
		)
		(property "Value" "4K7R2F-GP"
			(at 0.064008 -3.993896 90)
			(unlocked yes)
			(layer "F.Fab")
			(hide yes)
			(effects
				(font
					(size 1.016 1.016)
					(thickness 0.1524)
				)
			)
		)
		(property "Device Type" "R402H16"
			(at 0.064008 -5.517896 90)
			(unlocked yes)
			(layer "F.Fab")
			(hide yes)
			(effects
				(font
					(size 1.016 1.016)
					(thickness 0.1524)
				)
			)
		)
		(duplicate_pad_numbers_are_jumpers no)
		(fp_line
			(start 0.508 -0.9398)
			(end -0.508 -0.9398)
			(stroke
				(width 0.1524)
				(type default)
			)
			(layer "F.SilkS")
		)
		(fp_line
			(start -0.508 -0.9398)
			(end -0.508 0.9398)
			(stroke
				(width 0.1524)
				(type default)
			)
			(layer "F.SilkS")
		)
		(fp_rect
			(start -0.508 0.9398)
			(end 0.508 -0.9398)
			(stroke
				(width 0)
				(type default)
			)
			(fill no)
			(layer "F.CrtYd")
		)
		(fp_rect
			(start -0.508 0.9398)
			(end 0.508 -0.9398)
			(stroke
				(width 0)
				(type default)
			)
			(fill no)
			(layer "F.Fab")
		)
		(pad "1" smd custom
			(at 0 -0.4445 90)
			(size 0.1397 0.1397)
			(layers "F.Cu" "F.Mask" "F.Paste")
			(net "P3V3")
			(options
				(clearance outline)
				(anchor circle)
			)
			(primitives
				(gr_poly
					(pts
						(arc
							(start -0.1778 -0.2794)
							(mid -0.249642 -0.249642)
							(end -0.2794 -0.1778)
						)
						(arc
							(start -0.2794 0.1778)
							(mid -0.249642 0.249642)
							(end -0.1778 0.2794)
						)
						(arc
							(start 0.1778 0.2794)
							(mid 0.249642 0.249642)
							(end 0.2794 0.1778)
						)
						(arc
							(start 0.2794 -0.1778)
							(mid 0.249642 -0.249642)
							(end 0.1778 -0.2794)
						)
					)
					(width 0)
					(fill yes)
				)
			)
		)
		(pad "2" smd custom
			(at 0 0.4445 90)
			(size 0.1397 0.1397)
			(layers "F.Cu" "F.Mask" "F.Paste")
			(net "PWM_OUT_FAN2")
			(options
				(clearance outline)
				(anchor circle)
			)
			(primitives
				(gr_poly
					(pts
						(arc
							(start -0.1778 -0.2794)
							(mid -0.249642 -0.249642)
							(end -0.2794 -0.1778)
						)
						(arc
							(start -0.2794 0.1778)
							(mid -0.249642 0.249642)
							(end -0.1778 0.2794)
						)
						(arc
							(start 0.1778 0.2794)
							(mid 0.249642 0.249642)
							(end 0.2794 0.1778)
						)
						(arc
							(start 0.2794 -0.1778)
							(mid 0.249642 -0.249642)
							(end 0.1778 -0.2794)
						)
					)
					(width 0)
					(fill yes)
				)
			)
		)
	)
	(footprint ""
		(layer "F.Cu")
		(at 17.907 -298.4754 -90)
		(property "Reference" "R92"
			(at 0 0 270)
			(layer "F.SilkS")
			(hide yes)
			(effects
				(font
					(size 1.27 1.27)
				)
			)
		)
		(property "Value" "4K7R2F-GP"
			(at 0.064008 -3.993896 270)
			(unlocked yes)
			(layer "F.Fab")
			(hide yes)
			(effects
				(font
					(size 1.016 1.016)
					(thickness 0.1524)
				)
			)
		)
		(property "Device Type" "R402H16"
			(at 0.064008 -5.517896 270)
			(unlocked yes)
			(layer "F.Fab")
			(hide yes)
			(effects
				(font
					(size 1.016 1.016)
					(thickness 0.1524)
				)
			)
		)
		(duplicate_pad_numbers_are_jumpers no)
		(fp_line
			(start -0.508 -0.9398)
			(end -0.508 0.9398)
			(stroke
				(width 0.1524)
				(type default)
			)
			(layer "F.SilkS")
		)
		(fp_line
			(start 0.508 -0.9398)
			(end -0.508 -0.9398)
			(stroke
				(width 0.1524)
				(type default)
			)
			(layer "F.SilkS")
		)
		(fp_rect
			(start -0.508 0.9398)
			(end 0.508 -0.9398)
			(stroke
				(width 0)
				(type default)
			)
			(fill no)
			(layer "F.CrtYd")
		)
		(fp_rect
			(start -0.508 0.9398)
			(end 0.508 -0.9398)
			(stroke
				(width 0)
				(type default)
			)
			(fill no)
			(layer "F.Fab")
		)
		(pad "1" smd custom
			(at 0 -0.4445 270)
			(size 0.1397 0.1397)
			(layers "F.Cu" "F.Mask" "F.Paste")
			(net "P12V")
			(options
				(clearance outline)
				(anchor circle)
			)
			(primitives
				(gr_poly
					(pts
						(arc
							(start -0.1778 -0.2794)
							(mid -0.249642 -0.249642)
							(end -0.2794 -0.1778)
						)
						(arc
							(start -0.2794 0.1778)
							(mid -0.249642 0.249642)
							(end -0.1778 0.2794)
						)
						(arc
							(start 0.1778 0.2794)
							(mid 0.249642 0.249642)
							(end 0.2794 0.1778)
						)
						(arc
							(start 0.2794 -0.1778)
							(mid 0.249642 -0.249642)
							(end 0.1778 -0.2794)
						)
					)
					(width 0)
					(fill yes)
				)
			)
		)
		(pad "2" smd custom
			(at 0 0.4445 270)
			(size 0.1397 0.1397)
			(layers "F.Cu" "F.Mask" "F.Paste")
			(net "PWM_OUT_FAN2_NET")
			(options
				(clearance outline)
				(anchor circle)
			)
			(primitives
				(gr_poly
					(pts
						(arc
							(start -0.1778 -0.2794)
							(mid -0.249642 -0.249642)
							(end -0.2794 -0.1778)
						)
						(arc
							(start -0.2794 0.1778)
							(mid -0.249642 0.249642)
							(end -0.1778 0.2794)
						)
						(arc
							(start 0.1778 0.2794)
							(mid 0.249642 0.249642)
							(end 0.2794 0.1778)
						)
						(arc
							(start 0.2794 -0.1778)
							(mid 0.249642 -0.249642)
							(end 0.1778 -0.2794)
						)
					)
					(width 0)
					(fill yes)
				)
			)
		)
	)
	(footprint ""
		(layer "F.Cu")
		(at 39.8018 -159.2072 90)
		(property "Reference" "TP12"
			(at 0 0 90)
			(layer "F.SilkS")
			(hide yes)
			(effects
				(font
					(size 1.27 1.27)
				)
			)
		)
		(property "Value" "TPAD32-GP"
			(at 0 -3.166364 90)
			(unlocked yes)
			(layer "F.Fab")
			(hide yes)
			(effects
				(font
					(size 1.016 1.016)
					(thickness 0.1524)
				)
			)
		)
		(property "Device Type" "TPAD32"
			(at 0 -4.690618 90)
			(unlocked yes)
			(layer "F.Fab")
			(hide yes)
			(effects
				(font
					(size 1.016 1.016)
					(thickness 0.1524)
				)
			)
		)
		(duplicate_pad_numbers_are_jumpers no)
		(fp_poly
			(pts
				(arc
					(start 0 0.7112)
					(mid 0 -0.7112)
					(end 0 0.7112)
				)
			)
			(stroke
				(width 0)
				(type default)
			)
			(fill no)
			(layer "F.CrtYd")
		)
		(fp_poly
			(pts
				(arc
					(start 0 0.7112)
					(mid 0 -0.7112)
					(end 0 0.7112)
				)
			)
			(stroke
				(width 0)
				(type default)
			)
			(fill no)
			(layer "F.Fab")
		)
		(pad "1" smd circle
			(at 0 0 90)
			(size 0.8128 0.8128)
			(layers "F.Cu" "F.Mask" "F.Paste")
			(net "NCT7904_PECI")
		)
	)
	(footprint ""
		(layer "F.Cu")
		(at 36.1442 -374.9802 180)
		(property "Reference" "PD1"
			(at 0 0 180)
			(layer "F.SilkS")
			(hide yes)
			(effects
				(font
					(size 1.27 1.27)
				)
			)
		)
		(property "Value" "MM3Z15VT1G-GP"
			(at 0 -6.7818 180)
			(unlocked yes)
			(layer "F.Fab")
			(hide yes)
			(effects
				(font
					(size 1.016 1.016)
					(thickness 0.1524)
				)
			)
		)
		(property "Device Type" "SOD323AKH44"
			(at 0 -8.6868 180)
			(unlocked yes)
			(layer "F.Fab")
			(hide yes)
			(effects
				(font
					(size 1.016 1.016)
					(thickness 0.1524)
				)
			)
		)
		(duplicate_pad_numbers_are_jumpers no)
		(fp_line
			(start 0.889 2.159)
			(end -0.889 2.159)
			(stroke
				(width 0.1524)
				(type default)
			)
			(layer "F.SilkS")
		)
		(fp_line
			(start 0.889 -1.9304)
			(end 0.889 2.159)
			(stroke
				(width 0.1524)
				(type default)
			)
			(layer "F.SilkS")
		)
		(fp_line
			(start 0.762 2.0574)
			(end -0.762 2.0574)
			(stroke
				(width 0.508)
				(type default)
			)
			(layer "F.SilkS")
		)
		(fp_line
			(start -0.889 2.159)
			(end -0.889 -1.9304)
			(stroke
				(width 0.1524)
				(type default)
			)
			(layer "F.SilkS")
		)
		(fp_line
			(start -0.889 -1.9304)
			(end 0.889 -1.9304)
			(stroke
				(width 0.1524)
				(type default)
			)
			(layer "F.SilkS")
		)
		(fp_rect
			(start -1.016 2.3114)
			(end 1.016 -2.0066)
			(stroke
				(width 0)
				(type default)
			)
			(fill no)
			(layer "F.CrtYd")
		)
		(fp_poly
			(pts
				(xy -1.016 -2.0066) (xy 1.016 -2.0066) (xy 1.016 2.3114) (xy -1.016 2.3114)
			)
			(stroke
				(width 0)
				(type default)
			)
			(fill no)
			(layer "F.Fab")
		)
		(pad "A" smd rect
			(at 0 -1.143 180)
			(size 0.5588 1.016)
			(layers "F.Cu" "F.Mask" "F.Paste")
			(net "ADM1276_GATE_RSV")
		)
		(pad "K" smd rect
			(at 0 1.143 180)
			(size 0.5588 1.016)
			(layers "F.Cu" "F.Mask" "F.Paste")
			(net "ADM1276_GATE")
		)
	)
	(footprint ""
		(layer "F.Cu")
		(at 32.7406 -149.071584 180)
		(property "Reference" "R36"
			(at 0 0 180)
			(layer "F.SilkS")
			(hide yes)
			(effects
				(font
					(size 1.27 1.27)
				)
			)
		)
		(property "Value" "110KR2F-L-GP"
			(at 0.064008 -3.993896 180)
			(unlocked yes)
			(layer "F.Fab")
			(hide yes)
			(effects
				(font
					(size 1.016 1.016)
					(thickness 0.1524)
				)
			)
		)
		(property "Device Type" "R402H16"
			(at 0.064008 -5.517896 180)
			(unlocked yes)
			(layer "F.Fab")
			(hide yes)
			(effects
				(font
					(size 1.016 1.016)
					(thickness 0.1524)
				)
			)
		)
		(duplicate_pad_numbers_are_jumpers no)
		(fp_line
			(start 0.508 -0.9398)
			(end -0.508 -0.9398)
			(stroke
				(width 0.1524)
				(type default)
			)
			(layer "F.SilkS")
		)
		(fp_line
			(start -0.508 -0.9398)
			(end -0.508 0.9398)
			(stroke
				(width 0.1524)
				(type default)
			)
			(layer "F.SilkS")
		)
		(fp_rect
			(start -0.508 0.9398)
			(end 0.508 -0.9398)
			(stroke
				(width 0)
				(type default)
			)
			(fill no)
			(layer "F.CrtYd")
		)
		(fp_rect
			(start -0.508 0.9398)
			(end 0.508 -0.9398)
			(stroke
				(width 0)
				(type default)
			)
			(fill no)
			(layer "F.Fab")
		)
		(pad "1" smd custom
			(at 0 -0.4445 180)
			(size 0.1397 0.1397)
			(layers "F.Cu" "F.Mask" "F.Paste")
			(net "P12VU")
			(options
				(clearance outline)
				(anchor circle)
			)
			(primitives
				(gr_poly
					(pts
						(arc
							(start -0.1778 -0.2794)
							(mid -0.249642 -0.249642)
							(end -0.2794 -0.1778)
						)
						(arc
							(start -0.2794 0.1778)
							(mid -0.249642 0.249642)
							(end -0.1778 0.2794)
						)
						(arc
							(start 0.1778 0.2794)
							(mid 0.249642 0.249642)
							(end 0.2794 0.1778)
						)
						(arc
							(start 0.2794 -0.1778)
							(mid 0.249642 -0.249642)
							(end 0.1778 -0.2794)
						)
					)
					(width 0)
					(fill yes)
				)
			)
		)
		(pad "2" smd custom
			(at 0 0.4445 180)
			(size 0.1397 0.1397)
			(layers "F.Cu" "F.Mask" "F.Paste")
			(net "NCT7904_VSEN7")
			(options
				(clearance outline)
				(anchor circle)
			)
			(primitives
				(gr_poly
					(pts
						(arc
							(start -0.1778 -0.2794)
							(mid -0.249642 -0.249642)
							(end -0.2794 -0.1778)
						)
						(arc
							(start -0.2794 0.1778)
							(mid -0.249642 0.249642)
							(end -0.1778 0.2794)
						)
						(arc
							(start 0.1778 0.2794)
							(mid 0.249642 0.249642)
							(end 0.2794 0.1778)
						)
						(arc
							(start 0.2794 -0.1778)
							(mid 0.249642 -0.249642)
							(end 0.1778 -0.2794)
						)
					)
					(width 0)
					(fill yes)
				)
			)
		)
	)
	(footprint ""
		(layer "F.Cu")
		(at 38.361366 -159.40151 90)
		(property "Reference" "TP15"
			(at 0 0 90)
			(layer "F.SilkS")
			(hide yes)
			(effects
				(font
					(size 1.27 1.27)
				)
			)
		)
		(property "Value" "TPAD32-GP"
			(at 0 -3.166364 90)
			(unlocked yes)
			(layer "F.Fab")
			(hide yes)
			(effects
				(font
					(size 1.016 1.016)
					(thickness 0.1524)
				)
			)
		)
		(property "Device Type" "TPAD32"
			(at 0 -4.690618 90)
			(unlocked yes)
			(layer "F.Fab")
			(hide yes)
			(effects
				(font
					(size 1.016 1.016)
					(thickness 0.1524)
				)
			)
		)
		(duplicate_pad_numbers_are_jumpers no)
		(fp_poly
			(pts
				(arc
					(start 0 0.7112)
					(mid 0 -0.7112)
					(end 0 0.7112)
				)
			)
			(stroke
				(width 0)
				(type default)
			)
			(fill no)
			(layer "F.CrtYd")
		)
		(fp_poly
			(pts
				(arc
					(start 0 0.7112)
					(mid 0 -0.7112)
					(end 0 0.7112)
				)
			)
			(stroke
				(width 0)
				(type default)
			)
			(fill no)
			(layer "F.Fab")
		)
		(pad "1" smd circle
			(at 0 0 90)
			(size 0.8128 0.8128)
			(layers "F.Cu" "F.Mask" "F.Paste")
			(net "NCT7904_THERMTRIP")
		)
	)
)
